# T6G (Grand Teton) — schematic netlist excerpt (pin names and nets, part order shuffled) for the footprints in the layout excerpt that follows; sources: Cadence DE-HDL packaged netlist, KiCad conversion of 04192023_DAF0TMB3IC0_F0TG_MB_C_brd_V02_OCP.brd

PR471  Q_RES  20K 1% CHIP  pkg 0402LF  page 209 : A = PVDD18_S5_P0_FB ; B = PVDD18_S5_P0_FB_RC
R3190  Q_RES  4.7K 1% CHIP  pkg 0402LF  page 139 : A = P3V3_AUX ; B = OCP_V3_2_PWRBRK_BUFF_N

(kicad_pcb
	(version 20260206)
	(generator "pcbnew")
	(generator_version "10.0")
	(general
		(thickness 1.6)
		(legacy_teardrops no)
	)
	(paper "A4")
	(title_block
		(title "04192023_DAF0TMB3IC0_F0TG_MB_C_brd_V02_OCP.brd")
		(comment 1 "Grand Teton / footprints 1217-1218 of 8354")
	)
	(layers
		(0 "F.Cu" signal "TOP")
		(4 "In1.Cu" signal "GND")
		(6 "In2.Cu" signal "IN1")
		(8 "In3.Cu" signal "GND1")
		(10 "In4.Cu" signal "IN2")
		(12 "In5.Cu" signal "GND2")
		(14 "In6.Cu" signal "IN3")
		(16 "In7.Cu" signal "GND3")
		(18 "In8.Cu" signal "VCC")
		(20 "In9.Cu" signal "VCC1")
		(22 "In10.Cu" signal "GND4")
		(24 "In11.Cu" signal "IN4")
		(26 "In12.Cu" signal "GND5")
		(28 "In13.Cu" signal "IN5")
		(30 "In14.Cu" signal "GND6")
		(32 "In15.Cu" signal "IN6")
		(34 "In16.Cu" signal "GND7")
		(2 "B.Cu" signal "BOTTOM")
		(9 "F.Adhes" user "F.Adhesive")
		(11 "B.Adhes" user "B.Adhesive")
		(13 "F.Paste" user "Package Geometry/Pastemask Top")
		(15 "B.Paste" user "Package Geometry/Pastemask Bottom")
		(5 "F.SilkS" user "Ref Des/Silkscreen Top")
		(7 "B.SilkS" user "Ref Des/Silkscreen Bottom")
		(1 "F.Mask" user "Board Geometry/Soldermask Top")
		(3 "B.Mask" user "Board Geometry/Soldermask Bottom")
		(17 "Dwgs.User" user "User.Drawings")
		(19 "Cmts.User" user "User.Comments")
		(21 "Eco1.User" user "User.Eco1")
		(23 "Eco2.User" user "User.Eco2")
		(25 "Edge.Cuts" user "Board Geometry/Outline")
		(27 "Margin" user)
		(31 "F.CrtYd" user "Package Geometry/Place Bound Top")
		(29 "B.CrtYd" user "Package Geometry/Place Bound Bottom")
		(35 "F.Fab" user "Ref Des/Assembly Top")
		(33 "B.Fab" user "Ref Des/Assembly Bottom")
	)
	(footprint ""
		(layer "F.Cu")
		(at 330.196444 -138.893042 90)
		(property "Reference" "PR471"
			(at 0 0 90)
			(layer "F.SilkS")
			(hide yes)
			(effects
				(font
					(size 1.27 1.27)
				)
			)
		)
		(property "Value" ""
			(at 0 0 90)
			(layer "F.Fab")
			(effects
				(font
					(size 1.27 1.27)
				)
			)
		)
		(duplicate_pad_numbers_are_jumpers no)
		(fp_line
			(start 0.7874 -0.4064)
			(end 0.7874 0.4064)
			(stroke
				(width 0.1524)
				(type default)
			)
			(layer "F.SilkS")
		)
		(fp_line
			(start -0.7874 -0.4064)
			(end 0.7874 -0.4064)
			(stroke
				(width 0.1524)
				(type default)
			)
			(layer "F.SilkS")
		)
		(fp_line
			(start 0.7874 0.4064)
			(end -0.7874 0.4064)
			(stroke
				(width 0.1524)
				(type default)
			)
			(layer "F.SilkS")
		)
		(fp_line
			(start -0.7874 0.4064)
			(end -0.7874 -0.4064)
			(stroke
				(width 0.1524)
				(type default)
			)
			(layer "F.SilkS")
		)
		(fp_line
			(start -0.12065 -0.305054)
			(end -0.12065 -0.2794)
			(stroke
				(width 0.1)
				(type default)
			)
			(layer "F.Fab")
		)
		(fp_line
			(start -0.67945 -0.305054)
			(end -0.12065 -0.305054)
			(stroke
				(width 0.1)
				(type default)
			)
			(layer "F.Fab")
		)
		(fp_line
			(start 0.67945 -0.3048)
			(end 0.67945 0.3048)
			(stroke
				(width 0.1)
				(type default)
			)
			(layer "F.Fab")
		)
		(fp_line
			(start 0.12065 -0.3048)
			(end 0.67945 -0.3048)
			(stroke
				(width 0.1)
				(type default)
			)
			(layer "F.Fab")
		)
		(fp_line
			(start 0.12065 -0.2794)
			(end 0.12065 -0.3048)
			(stroke
				(width 0.1)
				(type default)
			)
			(layer "F.Fab")
		)
		(fp_line
			(start -0.12065 -0.2794)
			(end 0.12065 -0.2794)
			(stroke
				(width 0.1)
				(type default)
			)
			(layer "F.Fab")
		)
		(fp_line
			(start 0.120396 0.2794)
			(end -0.12065 0.2794)
			(stroke
				(width 0.1)
				(type default)
			)
			(layer "F.Fab")
		)
		(fp_line
			(start -0.12065 0.2794)
			(end -0.12065 0.3048)
			(stroke
				(width 0.1)
				(type default)
			)
			(layer "F.Fab")
		)
		(fp_line
			(start 0.67945 0.3048)
			(end 0.120396 0.3048)
			(stroke
				(width 0.1)
				(type default)
			)
			(layer "F.Fab")
		)
		(fp_line
			(start 0.120396 0.3048)
			(end 0.120396 0.2794)
			(stroke
				(width 0.1)
				(type default)
			)
			(layer "F.Fab")
		)
		(fp_line
			(start -0.12065 0.3048)
			(end -0.67945 0.3048)
			(stroke
				(width 0.1)
				(type default)
			)
			(layer "F.Fab")
		)
		(fp_line
			(start -0.67945 0.3048)
			(end -0.67945 -0.305054)
			(stroke
				(width 0.1)
				(type default)
			)
			(layer "F.Fab")
		)
		(pad "1" smd circle
			(at -0.40005 0 90)
			(size 0 0)
			(layers "F.Cu" "F.Mask" "F.Paste")
			(net "PVDD18_S5_P0_FB")
		)
		(pad "2" smd circle
			(at 0.40005 0 90)
			(size 0 0)
			(layers "F.Cu" "F.Mask" "F.Paste")
			(net "PVDD18_S5_P0_FB_RC")
		)
	)
	(footprint ""
		(layer "F.Cu")
		(at 257.951478 -108.179108 180)
		(property "Reference" "R3190"
			(at 0 0 180)
			(layer "F.SilkS")
			(hide yes)
			(effects
				(font
					(size 1.27 1.27)
				)
			)
		)
		(property "Value" ""
			(at 0 0 180)
			(layer "F.Fab")
			(effects
				(font
					(size 1.27 1.27)
				)
			)
		)
		(duplicate_pad_numbers_are_jumpers no)
		(fp_line
			(start 0.7874 0.4064)
			(end -0.7874 0.4064)
			(stroke
				(width 0.1524)
				(type default)
			)
			(layer "F.SilkS")
		)
		(fp_line
			(start 0.7874 -0.4064)
			(end 0.7874 0.4064)
			(stroke
				(width 0.1524)
				(type default)
			)
			(layer "F.SilkS")
		)
		(fp_line
			(start -0.7874 0.4064)
			(end -0.7874 -0.4064)
			(stroke
				(width 0.1524)
				(type default)
			)
			(layer "F.SilkS")
		)
		(fp_line
			(start -0.7874 -0.4064)
			(end 0.7874 -0.4064)
			(stroke
				(width 0.1524)
				(type default)
			)
			(layer "F.SilkS")
		)
		(fp_line
			(start 0.67945 0.3048)
			(end 0.120396 0.3048)
			(stroke
				(width 0.1)
				(type default)
			)
			(layer "F.Fab")
		)
		(fp_line
			(start 0.67945 -0.3048)
			(end 0.67945 0.3048)
			(stroke
				(width 0.1)
				(type default)
			)
			(layer "F.Fab")
		)
		(fp_line
			(start 0.12065 -0.2794)
			(end 0.12065 -0.3048)
			(stroke
				(width 0.1)
				(type default)
			)
			(layer "F.Fab")
		)
		(fp_line
			(start 0.12065 -0.3048)
			(end 0.67945 -0.3048)
			(stroke
				(width 0.1)
				(type default)
			)
			(layer "F.Fab")
		)
		(fp_line
			(start 0.120396 0.3048)
			(end 0.120396 0.2794)
			(stroke
				(width 0.1)
				(type default)
			)
			(layer "F.Fab")
		)
		(fp_line
			(start 0.120396 0.2794)
			(end -0.12065 0.2794)
			(stroke
				(width 0.1)
				(type default)
			)
			(layer "F.Fab")
		)
		(fp_line
			(start -0.12065 0.3048)
			(end -0.67945 0.3048)
			(stroke
				(width 0.1)
				(type default)
			)
			(layer "F.Fab")
		)
		(fp_line
			(start -0.12065 0.2794)
			(end -0.12065 0.3048)
			(stroke
				(width 0.1)
				(type default)
			)
			(layer "F.Fab")
		)
		(fp_line
			(start -0.12065 -0.2794)
			(end 0.12065 -0.2794)
			(stroke
				(width 0.1)
				(type default)
			)
			(layer "F.Fab")
		)
		(fp_line
			(start -0.12065 -0.305054)
			(end -0.12065 -0.2794)
			(stroke
				(width 0.1)
				(type default)
			)
			(layer "F.Fab")
		)
		(fp_line
			(start -0.67945 0.3048)
			(end -0.67945 -0.305054)
			(stroke
				(width 0.1)
				(type default)
			)
			(layer "F.Fab")
		)
		(fp_line
			(start -0.67945 -0.305054)
			(end -0.12065 -0.305054)
			(stroke
				(width 0.1)
				(type default)
			)
			(layer "F.Fab")
		)
		(pad "1" smd circle
			(at -0.40005 0 180)
			(size 0 0)
			(layers "F.Cu" "F.Mask" "F.Paste")
			(net "P3V3_AUX")
		)
		(pad "2" smd circle
			(at 0.40005 0 180)
			(size 0 0)
			(layers "F.Cu" "F.Mask" "F.Paste")
			(net "OCP_V3_2_PWRBRK_BUFF_N")
		)
	)
)
